(kicad_pcb
	(version 20260206)
	(generator "pcbnew")
	(generator_version "10.0")
	(general
		(thickness 1.6)
		(legacy_teardrops no)
	)
	(paper "A4")
	(title_block
		(title "Wiwynn_Tioga_Pass_MB.brd")
		(comment 1 "Tioga Pass / footprints 3469-3476 of 4770")
	)
	(layers
		(0 "F.Cu" signal "TOP")
		(4 "In1.Cu" signal "L2GND")
		(6 "In2.Cu" signal "L3")
		(8 "In3.Cu" signal "L4GND")
		(10 "In4.Cu" signal "L5")
		(12 "In5.Cu" signal "L6GND")
		(14 "In6.Cu" signal "L7VCC")
		(16 "In7.Cu" signal "L8VCC")
		(18 "In8.Cu" signal "L9GND")
		(20 "In9.Cu" signal "L10")
		(22 "In10.Cu" signal "L11GND")
		(24 "In11.Cu" signal "L12")
		(26 "In12.Cu" signal "L13GND")
		(2 "B.Cu" signal "BOTTOM")
		(9 "F.Adhes" user "F.Adhesive")
		(11 "B.Adhes" user "B.Adhesive")
		(13 "F.Paste" user "Package Geometry/Pastemask Top")
		(15 "B.Paste" user "Package Geometry/Pastemask Bottom")
		(5 "F.SilkS" user "Ref Des/Silkscreen Top")
		(7 "B.SilkS" user "Ref Des/Silkscreen Bottom")
		(1 "F.Mask" user "Board Geometry/Soldermask Top")
		(3 "B.Mask" user "Board Geometry/Soldermask Bottom")
		(17 "Dwgs.User" user "User.Drawings")
		(19 "Cmts.User" user "User.Comments")
		(21 "Eco1.User" user "User.Eco1")
		(23 "Eco2.User" user "User.Eco2")
		(25 "Edge.Cuts" user "Board Geometry/Outline")
		(27 "Margin" user)
		(31 "F.CrtYd" user "Package Geometry/Place Bound Top")
		(29 "B.CrtYd" user "Package Geometry/Place Bound Bottom")
		(35 "F.Fab" user "Ref Des/Assembly Top")
		(33 "B.Fab" user "Ref Des/Assembly Bottom")
	)
	(footprint ""
		(layer "B.Cu")
		(at 228.1174 -86.614 90)
		(property "Reference" "R4C5"
			(at 0.8382 -0.67818 90)
			(unlocked yes)
			(layer "B.SilkS")
			(effects
				(font
					(size 0.4064 0.254)
					(thickness 0.1524)
				)
				(justify left mirror)
			)
		)
		(property "Value" ""
			(at 0 0 90)
			(layer "B.Fab")
			(effects
				(font
					(size 1.27 1.27)
				)
				(justify mirror)
			)
		)
		(duplicate_pad_numbers_are_jumpers no)
		(fp_poly
			(pts
				(xy 0.2794 -0.1016) (xy -0.2794 -0.1016) (xy -0.2794 0.9906) (xy 0.2794 0.9906)
			)
			(stroke
				(width 0)
				(type default)
			)
			(fill no)
			(layer "B.CrtYd")
		)
		(fp_line
			(start 0.2794 -0.1016)
			(end 0.2794 0.9906)
			(stroke
				(width 0.1)
				(type default)
			)
			(layer "B.Fab")
		)
		(fp_line
			(start -0.2794 -0.1016)
			(end 0.2794 -0.1016)
			(stroke
				(width 0.1)
				(type default)
			)
			(layer "B.Fab")
		)
		(fp_line
			(start 0.2794 0.9906)
			(end -0.2794 0.9906)
			(stroke
				(width 0.1)
				(type default)
			)
			(layer "B.Fab")
		)
		(fp_line
			(start -0.2794 0.9906)
			(end -0.2794 -0.1016)
			(stroke
				(width 0.1)
				(type default)
			)
			(layer "B.Fab")
		)
		(pad "1" smd rect
			(at 0 0 270)
			(size 0.508 0.508)
			(layers "B.Cu" "B.Mask" "B.Paste")
			(net "VSENSE_PVSA_CPU0_P")
		)
		(pad "2" smd rect
			(at 0 0.889 270)
			(size 0.508 0.508)
			(layers "B.Cu" "B.Mask" "B.Paste")
			(net "PVSA_CPU0")
		)
		(zone
			(layer "B.Cu")
			(hatch none 0.5)
			(connect_pads
				(clearance 0)
			)
			(min_thickness 0.25)
			(keepout
				(tracks allowed)
				(vias not_allowed)
				(pads allowed)
				(copperpour not_allowed)
				(footprints allowed)
			)
			(placement
				(enabled no)
				(sheetname "")
			)
			(fill
				(thermal_gap 0.5)
				(thermal_bridge_width 0.5)
				(island_removal_mode 0)
			)
			(polygon
				(pts
					(xy 228.3714 -86.868) (xy 228.3714 -86.36) (xy 228.7524 -86.36) (xy 228.7524 -86.868)
				)
			)
		)
		(zone
			(layer "B.Cu")
			(hatch none 0.5)
			(connect_pads
				(clearance 0)
			)
			(min_thickness 0.25)
			(keepout
				(tracks not_allowed)
				(vias allowed)
				(pads allowed)
				(copperpour not_allowed)
				(footprints allowed)
			)
			(placement
				(enabled no)
				(sheetname "")
			)
			(fill
				(thermal_gap 0.5)
				(thermal_bridge_width 0.5)
				(island_removal_mode 0)
			)
			(polygon
				(pts
					(xy 228.7524 -86.868) (xy 228.7524 -86.36) (xy 228.3714 -86.36) (xy 228.3714 -86.868)
				)
			)
		)
	)
	(footprint ""
		(layer "B.Cu")
		(at 436.626 -52.3875)
		(property "Reference" "C2R18"
			(at 0 0 0)
			(layer "B.SilkS")
			(hide yes)
			(effects
				(font
					(size 1.27 1.27)
				)
				(justify mirror)
			)
		)
		(property "Value" ""
			(at 0 0 0)
			(layer "B.Fab")
			(effects
				(font
					(size 1.27 1.27)
				)
				(justify mirror)
			)
		)
		(duplicate_pad_numbers_are_jumpers no)
		(fp_poly
			(pts
				(xy -0.3048 -0.1016) (xy -0.3048 0.9906) (xy 0.3048 0.9906) (xy 0.3048 -0.1016)
			)
			(stroke
				(width 0)
				(type default)
			)
			(fill no)
			(layer "B.CrtYd")
		)
		(fp_line
			(start -0.3048 -0.1016)
			(end 0.3048 -0.1016)
			(stroke
				(width 0.1)
				(type default)
			)
			(layer "B.Fab")
		)
		(fp_line
			(start -0.3048 0.9906)
			(end -0.3048 -0.1016)
			(stroke
				(width 0.1)
				(type default)
			)
			(layer "B.Fab")
		)
		(fp_line
			(start 0.3048 -0.1016)
			(end 0.3048 0.9906)
			(stroke
				(width 0.1)
				(type default)
			)
			(layer "B.Fab")
		)
		(fp_line
			(start 0.3048 0.9906)
			(end -0.3048 0.9906)
			(stroke
				(width 0.1)
				(type default)
			)
			(layer "B.Fab")
		)
		(pad "1" smd rect
			(at 0 0 180)
			(size 0.508 0.508)
			(layers "B.Cu" "B.Mask" "B.Paste")
			(net "P12V_STBY")
		)
		(pad "2" smd rect
			(at 0 0.889 180)
			(size 0.508 0.508)
			(layers "B.Cu" "B.Mask" "B.Paste")
			(net "GND")
		)
		(zone
			(layer "B.Cu")
			(hatch none 0.5)
			(connect_pads
				(clearance 0)
			)
			(min_thickness 0.25)
			(keepout
				(tracks allowed)
				(vias not_allowed)
				(pads allowed)
				(copperpour not_allowed)
				(footprints allowed)
			)
			(placement
				(enabled no)
				(sheetname "")
			)
			(fill
				(thermal_gap 0.5)
				(thermal_bridge_width 0.5)
				(island_removal_mode 0)
			)
			(polygon
				(pts
					(xy 436.88 -52.1335) (xy 436.372 -52.1335) (xy 436.372 -51.7525) (xy 436.88 -51.7525)
				)
			)
		)
		(zone
			(layer "B.Cu")
			(hatch none 0.5)
			(connect_pads
				(clearance 0)
			)
			(min_thickness 0.25)
			(keepout
				(tracks not_allowed)
				(vias allowed)
				(pads allowed)
				(copperpour not_allowed)
				(footprints allowed)
			)
			(placement
				(enabled no)
				(sheetname "")
			)
			(fill
				(thermal_gap 0.5)
				(thermal_bridge_width 0.5)
				(island_removal_mode 0)
			)
			(polygon
				(pts
					(xy 436.88 -51.7525) (xy 436.372 -51.7525) (xy 436.372 -52.1335) (xy 436.88 -52.1335)
				)
			)
		)
	)
	(footprint ""
		(layer "B.Cu")
		(at 155.194 -17.78 90)
		(property "Reference" "C7T2"
			(at 0 0 90)
			(layer "B.SilkS")
			(hide yes)
			(effects
				(font
					(size 1.27 1.27)
				)
				(justify mirror)
			)
		)
		(property "Value" ""
			(at 0 0 90)
			(layer "B.Fab")
			(effects
				(font
					(size 1.27 1.27)
				)
				(justify mirror)
			)
		)
		(duplicate_pad_numbers_are_jumpers no)
		(fp_poly
			(pts
				(xy 0.4953 -0.2032) (xy -0.4953 -0.2032) (xy -0.4953 1.6002) (xy 0.4953 1.6002)
			)
			(stroke
				(width 0)
				(type default)
			)
			(fill no)
			(layer "B.CrtYd")
		)
		(fp_line
			(start 0.4953 -0.2032)
			(end -0.4953 -0.2032)
			(stroke
				(width 0.1)
				(type default)
			)
			(layer "B.Fab")
		)
		(fp_line
			(start -0.4953 -0.2032)
			(end -0.4953 1.6002)
			(stroke
				(width 0.1)
				(type default)
			)
			(layer "B.Fab")
		)
		(fp_line
			(start 0.4953 1.6002)
			(end 0.4953 -0.2032)
			(stroke
				(width 0.1)
				(type default)
			)
			(layer "B.Fab")
		)
		(fp_line
			(start -0.4953 1.6002)
			(end 0.4953 1.6002)
			(stroke
				(width 0.1)
				(type default)
			)
			(layer "B.Fab")
		)
		(pad "1" smd rect
			(at 0 0 270)
			(size 0.762 0.889)
			(layers "B.Cu" "B.Mask" "B.Paste")
			(net "PVPP_GHJ")
		)
		(pad "2" smd rect
			(at 0 1.397 270)
			(size 0.762 0.889)
			(layers "B.Cu" "B.Mask" "B.Paste")
			(net "GND")
		)
		(zone
			(layer "B.Cu")
			(hatch none 0.5)
			(connect_pads
				(clearance 0)
			)
			(min_thickness 0.25)
			(keepout
				(tracks not_allowed)
				(vias allowed)
				(pads allowed)
				(copperpour not_allowed)
				(footprints allowed)
			)
			(placement
				(enabled no)
				(sheetname "")
			)
			(fill
				(thermal_gap 0.5)
				(thermal_bridge_width 0.5)
				(island_removal_mode 0)
			)
			(polygon
				(pts
					(xy 155.6385 -18.161) (xy 155.6385 -17.399) (xy 156.1465 -17.399) (xy 156.1465 -18.161)
				)
			)
		)
	)
	(footprint ""
		(layer "B.Cu")
		(at 347.469206 4.370578 -90)
		(property "Reference" "C3U9"
			(at 0 0 90)
			(layer "B.SilkS")
			(hide yes)
			(effects
				(font
					(size 1.27 1.27)
				)
				(justify mirror)
			)
		)
		(property "Value" ""
			(at 0 0 90)
			(layer "B.Fab")
			(effects
				(font
					(size 1.27 1.27)
				)
				(justify mirror)
			)
		)
		(duplicate_pad_numbers_are_jumpers no)
		(fp_rect
			(start 0.7239 1.9939)
			(end -0.7239 -0.2159)
			(stroke
				(width 0)
				(type default)
			)
			(fill no)
			(layer "B.CrtYd")
		)
		(fp_line
			(start -0.7239 1.9939)
			(end -0.7239 -0.2159)
			(stroke
				(width 0.1)
				(type default)
			)
			(layer "B.Fab")
		)
		(fp_line
			(start 0.7239 1.9939)
			(end -0.7239 1.9939)
			(stroke
				(width 0.1)
				(type default)
			)
			(layer "B.Fab")
		)
		(fp_line
			(start -0.7239 -0.2159)
			(end 0.7239 -0.2159)
			(stroke
				(width 0.1)
				(type default)
			)
			(layer "B.Fab")
		)
		(fp_line
			(start 0.7239 -0.2159)
			(end 0.7239 1.9939)
			(stroke
				(width 0.1)
				(type default)
			)
			(layer "B.Fab")
		)
		(pad "1" smd rect
			(at 0 0 90)
			(size 1.27 1.016)
			(layers "B.Cu" "B.Mask" "B.Paste")
			(net "VR_FET_SW_P12V_STBY_PVDDQ_ABC")
		)
		(pad "2" smd rect
			(at 0 1.778 90)
			(size 1.27 1.016)
			(layers "B.Cu" "B.Mask" "B.Paste")
			(net "GND")
		)
		(zone
			(layer "B.Cu")
			(hatch none 0.5)
			(connect_pads
				(clearance 0)
			)
			(min_thickness 0.25)
			(keepout
				(tracks not_allowed)
				(vias allowed)
				(pads allowed)
				(copperpour not_allowed)
				(footprints allowed)
			)
			(placement
				(enabled no)
				(sheetname "")
			)
			(fill
				(thermal_gap 0.5)
				(thermal_bridge_width 0.5)
				(island_removal_mode 0)
			)
			(polygon
				(pts
					(xy 346.199206 5.005578) (xy 346.961206 5.005578) (xy 346.961206 3.735578) (xy 346.199206 3.735578)
				)
			)
		)
	)
	(footprint ""
		(layer "B.Cu")
		(at 176.212754 -83.947 -90)
		(property "Reference" "R6P11"
			(at 0 0 90)
			(layer "B.SilkS")
			(hide yes)
			(effects
				(font
					(size 1.27 1.27)
				)
				(justify mirror)
			)
		)
		(property "Value" ""
			(at 0 0 90)
			(layer "B.Fab")
			(effects
				(font
					(size 1.27 1.27)
				)
				(justify mirror)
			)
		)
		(duplicate_pad_numbers_are_jumpers no)
		(fp_poly
			(pts
				(xy 0.2794 -0.1016) (xy -0.2794 -0.1016) (xy -0.2794 0.9906) (xy 0.2794 0.9906)
			)
			(stroke
				(width 0)
				(type default)
			)
			(fill no)
			(layer "B.CrtYd")
		)
		(fp_line
			(start -0.2794 0.9906)
			(end -0.2794 -0.1016)
			(stroke
				(width 0.1)
				(type default)
			)
			(layer "B.Fab")
		)
		(fp_line
			(start 0.2794 0.9906)
			(end -0.2794 0.9906)
			(stroke
				(width 0.1)
				(type default)
			)
			(layer "B.Fab")
		)
		(fp_line
			(start -0.2794 -0.1016)
			(end 0.2794 -0.1016)
			(stroke
				(width 0.1)
				(type default)
			)
			(layer "B.Fab")
		)
		(fp_line
			(start 0.2794 -0.1016)
			(end 0.2794 0.9906)
			(stroke
				(width 0.1)
				(type default)
			)
			(layer "B.Fab")
		)
		(pad "1" smd rect
			(at 0 0 90)
			(size 0.508 0.508)
			(layers "B.Cu" "B.Mask" "B.Paste")
			(net "CLK_100M_CPU0_PE_REFCLK_DP")
		)
		(pad "2" smd rect
			(at 0 0.889 90)
			(size 0.508 0.508)
			(layers "B.Cu" "B.Mask" "B.Paste")
			(net "GND")
		)
		(zone
			(layer "B.Cu")
			(hatch none 0.5)
			(connect_pads
				(clearance 0)
			)
			(min_thickness 0.25)
			(keepout
				(tracks not_allowed)
				(vias allowed)
				(pads allowed)
				(copperpour not_allowed)
				(footprints allowed)
			)
			(placement
				(enabled no)
				(sheetname "")
			)
			(fill
				(thermal_gap 0.5)
				(thermal_bridge_width 0.5)
				(island_removal_mode 0)
			)
			(polygon
				(pts
					(xy 175.577754 -83.693) (xy 175.577754 -84.201) (xy 175.958754 -84.201) (xy 175.958754 -83.693)
				)
			)
		)
		(zone
			(layer "B.Cu")
			(hatch none 0.5)
			(connect_pads
				(clearance 0)
			)
			(min_thickness 0.25)
			(keepout
				(tracks allowed)
				(vias not_allowed)
				(pads allowed)
				(copperpour not_allowed)
				(footprints allowed)
			)
			(placement
				(enabled no)
				(sheetname "")
			)
			(fill
				(thermal_gap 0.5)
				(thermal_bridge_width 0.5)
				(island_removal_mode 0)
			)
			(polygon
				(pts
					(xy 175.958754 -83.693) (xy 175.958754 -84.201) (xy 175.577754 -84.201) (xy 175.577754 -83.693)
				)
			)
		)
	)
	(footprint ""
		(layer "B.Cu")
		(at 181.864 -145.796 180)
		(property "Reference" "R6L11"
			(at 0 0 0)
			(layer "B.SilkS")
			(hide yes)
			(effects
				(font
					(size 1.27 1.27)
				)
				(justify mirror)
			)
		)
		(property "Value" ""
			(at 0 0 0)
			(layer "B.Fab")
			(effects
				(font
					(size 1.27 1.27)
				)
				(justify mirror)
			)
		)
		(duplicate_pad_numbers_are_jumpers no)
		(fp_rect
			(start -0.2794 0.9906)
			(end 0.2794 -0.1016)
			(stroke
				(width 0)
				(type default)
			)
			(fill no)
			(layer "B.CrtYd")
		)
		(fp_line
			(start 0.2794 0.9906)
			(end -0.2794 0.9906)
			(stroke
				(width 0.1)
				(type default)
			)
			(layer "B.Fab")
		)
		(fp_line
			(start 0.2794 -0.1016)
			(end 0.2794 0.9906)
			(stroke
				(width 0.1)
				(type default)
			)
			(layer "B.Fab")
		)
		(fp_line
			(start -0.2794 0.9906)
			(end -0.2794 -0.1016)
			(stroke
				(width 0.1)
				(type default)
			)
			(layer "B.Fab")
		)
		(fp_line
			(start -0.2794 -0.1016)
			(end 0.2794 -0.1016)
			(stroke
				(width 0.1)
				(type default)
			)
			(layer "B.Fab")
		)
		(pad "1" smd rect
			(at 0 0)
			(size 0.508 0.508)
			(layers "B.Cu" "B.Mask" "B.Paste")
			(net "P3V3")
		)
		(pad "2" smd rect
			(at 0 0.889)
			(size 0.508 0.508)
			(layers "B.Cu" "B.Mask" "B.Paste")
			(net "VR_PVTT_DEF_BIAS")
		)
		(zone
			(layer "B.Cu")
			(hatch none 0.5)
			(connect_pads
				(clearance 0)
			)
			(min_thickness 0.25)
			(keepout
				(tracks not_allowed)
				(vias allowed)
				(pads allowed)
				(copperpour not_allowed)
				(footprints allowed)
			)
			(placement
				(enabled no)
				(sheetname "")
			)
			(fill
				(thermal_gap 0.5)
				(thermal_bridge_width 0.5)
				(island_removal_mode 0)
			)
			(polygon
				(pts
					(xy 182.118 -146.431) (xy 181.61 -146.431) (xy 181.61 -146.05) (xy 182.118 -146.05)
				)
			)
		)
		(zone
			(layer "B.Cu")
			(hatch none 0.5)
			(connect_pads
				(clearance 0)
			)
			(min_thickness 0.25)
			(keepout
				(tracks allowed)
				(vias not_allowed)
				(pads allowed)
				(copperpour not_allowed)
				(footprints allowed)
			)
			(placement
				(enabled no)
				(sheetname "")
			)
			(fill
				(thermal_gap 0.5)
				(thermal_bridge_width 0.5)
				(island_removal_mode 0)
			)
			(polygon
				(pts
					(xy 182.118 -146.431) (xy 181.61 -146.431) (xy 181.61 -146.05) (xy 182.118 -146.05)
				)
			)
		)
	)
	(footprint ""
		(layer "B.Cu")
		(at 2.54 -59.944 -90)
		(property "Reference" "C9R6"
			(at 0 0 90)
			(layer "B.SilkS")
			(hide yes)
			(effects
				(font
					(size 1.27 1.27)
				)
				(justify mirror)
			)
		)
		(property "Value" ""
			(at 0 0 90)
			(layer "B.Fab")
			(effects
				(font
					(size 1.27 1.27)
				)
				(justify mirror)
			)
		)
		(duplicate_pad_numbers_are_jumpers no)
		(fp_rect
			(start 0.3048 -0.1016)
			(end -0.3048 0.9906)
			(stroke
				(width 0)
				(type default)
			)
			(fill no)
			(layer "B.CrtYd")
		)
		(fp_line
			(start -0.3048 0.9906)
			(end -0.3048 -0.1016)
			(stroke
				(width 0.1)
				(type default)
			)
			(layer "B.Fab")
		)
		(fp_line
			(start 0.3048 0.9906)
			(end -0.3048 0.9906)
			(stroke
				(width 0.1)
				(type default)
			)
			(layer "B.Fab")
		)
		(fp_line
			(start -0.3048 -0.1016)
			(end 0.3048 -0.1016)
			(stroke
				(width 0.1)
				(type default)
			)
			(layer "B.Fab")
		)
		(fp_line
			(start 0.3048 -0.1016)
			(end 0.3048 0.9906)
			(stroke
				(width 0.1)
				(type default)
			)
			(layer "B.Fab")
		)
		(pad "1" smd rect
			(at 0 0 90)
			(size 0.508 0.508)
			(layers "B.Cu" "B.Mask" "B.Paste")
			(net "P12V_PSU")
		)
		(pad "2" smd rect
			(at 0 0.889 90)
			(size 0.508 0.508)
			(layers "B.Cu" "B.Mask" "B.Paste")
			(net "GND")
		)
		(zone
			(layer "B.Cu")
			(hatch none 0.5)
			(connect_pads
				(clearance 0)
			)
			(min_thickness 0.25)
			(keepout
				(tracks allowed)
				(vias not_allowed)
				(pads allowed)
				(copperpour not_allowed)
				(footprints allowed)
			)
			(placement
				(enabled no)
				(sheetname "")
			)
			(fill
				(thermal_gap 0.5)
				(thermal_bridge_width 0.5)
				(island_removal_mode 0)
			)
			(polygon
				(pts
					(xy 2.286 -59.69) (xy 2.286 -60.198) (xy 1.905 -60.198) (xy 1.905 -59.69)
				)
			)
		)
		(zone
			(layer "B.Cu")
			(hatch none 0.5)
			(connect_pads
				(clearance 0)
			)
			(min_thickness 0.25)
			(keepout
				(tracks not_allowed)
				(vias allowed)
				(pads allowed)
				(copperpour not_allowed)
				(footprints allowed)
			)
			(placement
				(enabled no)
				(sheetname "")
			)
			(fill
				(thermal_gap 0.5)
				(thermal_bridge_width 0.5)
				(island_removal_mode 0)
			)
			(polygon
				(pts
					(xy 2.286 -59.69) (xy 2.286 -60.198) (xy 1.905 -60.198) (xy 1.905 -59.69)
				)
			)
		)
	)
	(footprint ""
		(layer "B.Cu")
		(at 99.415854 -79.60614 180)
		(property "Reference" "C8P12"
			(at 0 0 0)
			(layer "B.SilkS")
			(hide yes)
			(effects
				(font
					(size 1.27 1.27)
				)
				(justify mirror)
			)
		)
		(property "Value" ""
			(at 0 0 0)
			(layer "B.Fab")
			(effects
				(font
					(size 1.27 1.27)
				)
				(justify mirror)
			)
		)
		(duplicate_pad_numbers_are_jumpers no)
		(fp_poly
			(pts
				(xy 0.7239 -0.2159) (xy -0.7239 -0.2159) (xy -0.7239 1.9939) (xy 0.7239 1.9939)
			)
			(stroke
				(width 0)
				(type default)
			)
			(fill no)
			(layer "B.CrtYd")
		)
		(fp_line
			(start 0.7239 1.9939)
			(end -0.7239 1.9939)
			(stroke
				(width 0.1)
				(type default)
			)
			(layer "B.Fab")
		)
		(fp_line
			(start 0.7239 -0.2159)
			(end 0.7239 1.9939)
			(stroke
				(width 0.1)
				(type default)
			)
			(layer "B.Fab")
		)
		(fp_line
			(start -0.7239 1.9939)
			(end -0.7239 -0.2159)
			(stroke
				(width 0.1)
				(type default)
			)
			(layer "B.Fab")
		)
		(fp_line
			(start -0.7239 -0.2159)
			(end 0.7239 -0.2159)
			(stroke
				(width 0.1)
				(type default)
			)
			(layer "B.Fab")
		)
		(pad "1" smd rect
			(at 0 0)
			(size 1.27 1.016)
			(layers "B.Cu" "B.Mask" "B.Paste")
			(net "PVCCIN_CPU1")
		)
		(pad "2" smd rect
			(at 0 1.778)
			(size 1.27 1.016)
			(layers "B.Cu" "B.Mask" "B.Paste")
			(net "GND")
		)
		(zone
			(layer "B.Cu")
			(hatch none 0.5)
			(connect_pads
				(clearance 0)
			)
			(min_thickness 0.25)
			(keepout
				(tracks not_allowed)
				(vias allowed)
				(pads allowed)
				(copperpour not_allowed)
				(footprints allowed)
			)
			(placement
				(enabled no)
				(sheetname "")
			)
			(fill
				(thermal_gap 0.5)
				(thermal_bridge_width 0.5)
				(island_removal_mode 0)
			)
			(polygon
				(pts
					(xy 98.780854 -80.11414) (xy 100.050854 -80.11414) (xy 100.050854 -80.87614) (xy 98.780854 -80.87614)
				)
			)
		)
	)
)
